(kicad_pcb
	(version 20260206)
	(generator "pcbnew")
	(generator_version "10.0")
	(general
		(thickness 1.6)
		(legacy_teardrops no)
	)
	(paper "A4")
	(title_block
		(title "Bryce Canyon_F.DPB_16315-1-OCP.brd")
		(comment 1 "Bryce Canyon / footprints 2172-2175 of 2223")
	)
	(layers
		(0 "F.Cu" signal "TOP")
		(4 "In1.Cu" signal "L2GND")
		(6 "In2.Cu" signal "L3")
		(8 "In3.Cu" signal "L4GND")
		(10 "In4.Cu" signal "L5")
		(12 "In5.Cu" signal "L6VCC")
		(14 "In6.Cu" signal "L7VCC")
		(16 "In7.Cu" signal "L8")
		(18 "In8.Cu" signal "L9GND")
		(20 "In9.Cu" signal "L10")
		(22 "In10.Cu" signal "L11GND")
		(2 "B.Cu" signal "BOTTOM")
		(9 "F.Adhes" user "F.Adhesive")
		(11 "B.Adhes" user "B.Adhesive")
		(13 "F.Paste" user "Package Geometry/Pastemask Top")
		(15 "B.Paste" user "Package Geometry/Pastemask Bottom")
		(5 "F.SilkS" user "Ref Des/Silkscreen Top")
		(7 "B.SilkS" user "Ref Des/Silkscreen Bottom")
		(1 "F.Mask" user "Board Geometry/Soldermask Top")
		(3 "B.Mask" user "Board Geometry/Soldermask Bottom")
		(17 "Dwgs.User" user "User.Drawings")
		(19 "Cmts.User" user "User.Comments")
		(21 "Eco1.User" user "User.Eco1")
		(23 "Eco2.User" user "User.Eco2")
		(25 "Edge.Cuts" user "Board Geometry/Outline")
		(27 "Margin" user)
		(31 "F.CrtYd" user "Package Geometry/Place Bound Top")
		(29 "B.CrtYd" user "Package Geometry/Place Bound Bottom")
		(35 "F.Fab" user "Ref Des/Assembly Top")
		(33 "B.Fab" user "Ref Des/Assembly Bottom")
	)
	(footprint ""
		(layer "B.Cu")
		(at 446.4304 -251.7648 -90)
		(property "Reference" "U22"
			(at 0 0 90)
			(layer "B.SilkS")
			(hide yes)
			(effects
				(font
					(size 1.27 1.27)
				)
				(justify mirror)
			)
		)
		(property "Value" "TPS53319DQPR-GP"
			(at -4.7498 -5.6896 270)
			(unlocked yes)
			(layer "B.Fab")
			(hide yes)
			(effects
				(font
					(size 1.016 1.016)
					(thickness 0.1524)
				)
				(justify mirror)
			)
		)
		(property "Device Type" "QFN22G6050-G6133H60"
			(at -4.7498 -7.2136 270)
			(unlocked yes)
			(layer "B.Fab")
			(hide yes)
			(effects
				(font
					(size 1.016 1.016)
					(thickness 0.1524)
				)
				(justify mirror)
			)
		)
		(duplicate_pad_numbers_are_jumpers no)
		(fp_line
			(start -3.556 3.5179)
			(end -3.556 2.2479)
			(stroke
				(width 0.1524)
				(type default)
			)
			(layer "B.SilkS")
		)
		(fp_line
			(start -2.286 3.5179)
			(end -3.556 3.5179)
			(stroke
				(width 0.1524)
				(type default)
			)
			(layer "B.SilkS")
		)
		(fp_line
			(start 3.556 3.5179)
			(end 2.286 3.5179)
			(stroke
				(width 0.1524)
				(type default)
			)
			(layer "B.SilkS")
		)
		(fp_line
			(start -1.500124 3.262122)
			(end -1.500124 4.024122)
			(stroke
				(width 0.1524)
				(type default)
			)
			(layer "B.SilkS")
		)
		(fp_line
			(start 0.999998 3.262122)
			(end 0.999998 3.770122)
			(stroke
				(width 0.1524)
				(type default)
			)
			(layer "B.SilkS")
		)
		(fp_line
			(start 3.556 2.2479)
			(end 3.556 3.5179)
			(stroke
				(width 0.1524)
				(type default)
			)
			(layer "B.SilkS")
		)
		(fp_line
			(start -0.500126 -3.262122)
			(end -0.500126 -3.770122)
			(stroke
				(width 0.1524)
				(type default)
			)
			(layer "B.SilkS")
		)
		(fp_line
			(start 1.999996 -3.262122)
			(end 1.999996 -4.024122)
			(stroke
				(width 0.1524)
				(type default)
			)
			(layer "B.SilkS")
		)
		(fp_line
			(start 2.286 -3.5179)
			(end 3.556 -3.5179)
			(stroke
				(width 0.1524)
				(type default)
			)
			(layer "B.SilkS")
		)
		(fp_line
			(start 3.556 -3.5179)
			(end 3.556 -2.2479)
			(stroke
				(width 0.1524)
				(type default)
			)
			(layer "B.SilkS")
		)
		(fp_poly
			(pts
				(xy -3.556 -3.5179) (xy -2.5273 -3.5179) (xy -3.556 -2.4892)
			)
			(stroke
				(width 0)
				(type default)
			)
			(fill yes)
			(layer "B.SilkS")
		)
		(fp_rect
			(start 2.9972 2.5019)
			(end -2.9972 -2.5019)
			(stroke
				(width 0)
				(type default)
			)
			(fill no)
			(layer "B.CrtYd")
		)
		(fp_poly
			(pts
				(xy -3.556 -2.5019) (xy 2.9972 -2.5019) (xy 2.9972 2.5019) (xy -2.9972 2.5019) (xy -2.9972 -2.4892)
				(xy -3.556 -2.4892) (xy -3.556 3.5179) (xy 3.556 3.5179) (xy 3.556 -3.5179) (xy -3.556 -3.5179)
			)
			(stroke
				(width 0)
				(type default)
			)
			(fill no)
			(layer "B.CrtYd")
		)
		(fp_rect
			(start 3.556 3.5179)
			(end -3.556 -3.5179)
			(stroke
				(width 0)
				(type default)
			)
			(fill no)
			(layer "B.Fab")
		)
		(pad "1" smd rect
			(at -2.500122 -2.449322 90)
			(size 0.3048 1.1176)
			(layers "B.Cu" "B.Mask" "B.Paste")
			(net "P5V_C_VFB")
		)
		(pad "2" smd rect
			(at -1.999996 -2.449322 90)
			(size 0.3048 1.1176)
			(layers "B.Cu" "B.Mask" "B.Paste")
			(net "P5V_C_EN_R")
		)
		(pad "3" smd rect
			(at -1.500124 -2.449322 90)
			(size 0.3048 1.1176)
			(layers "B.Cu" "B.Mask" "B.Paste")
			(net "P5V_A_3_PGOOD")
		)
		(pad "4" smd rect
			(at -0.999998 -2.449322 90)
			(size 0.3048 1.1176)
			(layers "B.Cu" "B.Mask" "B.Paste")
			(net "P5V_C_VBST")
		)
		(pad "5" smd rect
			(at -0.500126 -2.449322 90)
			(size 0.3048 1.1176)
			(layers "B.Cu" "B.Mask" "B.Paste")
			(net "P5V_C_ROVP")
		)
		(pad "6" smd rect
			(at 0 -2.449322 90)
			(size 0.3048 1.1176)
			(layers "B.Cu" "B.Mask" "B.Paste")
			(net "P5V_C_LL")
		)
		(pad "7" smd rect
			(at 0.500126 -2.449322 90)
			(size 0.3048 1.1176)
			(layers "B.Cu" "B.Mask" "B.Paste")
			(net "P5V_C_LL")
		)
		(pad "8" smd rect
			(at 0.999998 -2.449322 90)
			(size 0.3048 1.1176)
			(layers "B.Cu" "B.Mask" "B.Paste")
			(net "P5V_C_LL")
		)
		(pad "9" smd rect
			(at 1.500124 -2.449322 90)
			(size 0.3048 1.1176)
			(layers "B.Cu" "B.Mask" "B.Paste")
			(net "P5V_C_LL")
		)
		(pad "10" smd rect
			(at 1.999996 -2.449322 90)
			(size 0.3048 1.1176)
			(layers "B.Cu" "B.Mask" "B.Paste")
			(net "P5V_C_LL")
		)
		(pad "11" smd rect
			(at 2.500122 -2.449322 90)
			(size 0.3048 1.1176)
			(layers "B.Cu" "B.Mask" "B.Paste")
			(net "P5V_C_LL")
		)
		(pad "12" smd rect
			(at 2.500122 2.449322 90)
			(size 0.3048 1.1176)
			(layers "B.Cu" "B.Mask" "B.Paste")
			(net "P12V_A_VIN_U22")
		)
		(pad "13" smd rect
			(at 1.999996 2.449322 90)
			(size 0.3048 1.1176)
			(layers "B.Cu" "B.Mask" "B.Paste")
			(net "P12V_A_VIN_U22")
		)
		(pad "14" smd rect
			(at 1.500124 2.449322 90)
			(size 0.3048 1.1176)
			(layers "B.Cu" "B.Mask" "B.Paste")
			(net "P12V_A_VIN_U22")
		)
		(pad "15" smd rect
			(at 0.999998 2.449322 90)
			(size 0.3048 1.1176)
			(layers "B.Cu" "B.Mask" "B.Paste")
			(net "P12V_A_VIN_U22")
		)
		(pad "16" smd rect
			(at 0.500126 2.449322 90)
			(size 0.3048 1.1176)
			(layers "B.Cu" "B.Mask" "B.Paste")
			(net "P12V_A_VIN_U22")
		)
		(pad "17" smd rect
			(at 0 2.449322 90)
			(size 0.3048 1.1176)
			(layers "B.Cu" "B.Mask" "B.Paste")
			(net "P12V_A_VIN_U22")
		)
		(pad "18" smd rect
			(at -0.500126 2.449322 90)
			(size 0.3048 1.1176)
			(layers "B.Cu" "B.Mask" "B.Paste")
			(net "P5V_C_VREG")
		)
		(pad "19" smd rect
			(at -0.999998 2.449322 90)
			(size 0.3048 1.1176)
			(layers "B.Cu" "B.Mask" "B.Paste")
			(net "P12V_A_VDD_U22")
		)
		(pad "20" smd rect
			(at -1.500124 2.449322 90)
			(size 0.3048 1.1176)
			(layers "B.Cu" "B.Mask" "B.Paste")
			(net "P5V_C_MODE")
		)
		(pad "21" smd rect
			(at -1.999996 2.449322 90)
			(size 0.3048 1.1176)
			(layers "B.Cu" "B.Mask" "B.Paste")
			(net "P5V_C_TRIP")
		)
		(pad "22" smd rect
			(at -2.500122 2.449322 90)
			(size 0.3048 1.1176)
			(layers "B.Cu" "B.Mask" "B.Paste")
			(net "P5V_C_RF")
		)
		(pad "23" smd custom
			(at 0 0 90)
			(size 0.83185 0.83185)
			(layers "B.Cu" "B.Mask" "B.Paste")
			(net "GND")
			(options
				(clearance outline)
				(anchor circle)
			)
			(primitives
				(gr_poly
					(pts
						(xy -2.7813 -1.6637) (xy -2.7813 -1.2954) (xy -3.048 -1.2954) (xy -3.048 -0.9525) (xy -2.7813 -0.9525)
						(xy -2.7813 0.9525) (xy -3.048 0.9525) (xy -3.048 1.2954) (xy -2.7813 1.2954) (xy -2.7813 1.6637)
						(xy 2.7813 1.6637) (xy 2.7813 1.2954) (xy 3.048 1.2954) (xy 3.048 0.9525) (xy 2.7813 0.9525) (xy 2.7813 -0.9525)
						(xy 3.048 -0.9525) (xy 3.048 -1.2954) (xy 2.7813 -1.2954) (xy 2.7813 -1.6637)
					)
					(width 0)
					(fill yes)
				)
			)
		)
	)
	(footprint ""
		(layer "B.Cu")
		(at 74.615802 -147.37715 -90)
		(property "Reference" "PG12"
			(at 0 0 90)
			(layer "B.SilkS")
			(hide yes)
			(effects
				(font
					(size 1.27 1.27)
				)
				(justify mirror)
			)
		)
		(property "Value" "GAP-CLOSE-PWR-4-GP"
			(at 2.4638 -0.5461 270)
			(unlocked yes)
			(layer "B.Fab")
			(hide yes)
			(effects
				(font
					(size 1.016 1.016)
					(thickness 0.1524)
				)
				(justify mirror)
			)
		)
		(property "Device Type" "GAP-CLOSE-PWR-4"
			(at 2.4638 -2.0701 270)
			(unlocked yes)
			(layer "B.Fab")
			(hide yes)
			(effects
				(font
					(size 1.016 1.016)
					(thickness 0.1524)
				)
				(justify mirror)
			)
		)
		(duplicate_pad_numbers_are_jumpers no)
		(fp_rect
			(start 0.2794 0.254)
			(end -0.2794 -0.254)
			(stroke
				(width 0)
				(type default)
			)
			(fill no)
			(layer "B.CrtYd")
		)
		(fp_rect
			(start 0.2794 0.254)
			(end -0.2794 -0.254)
			(stroke
				(width 0)
				(type default)
			)
			(fill no)
			(layer "B.Fab")
		)
		(pad "1" smd rect
			(at 0.0635 0 90)
			(size 0.1778 0.254)
			(layers "B.Cu" "B.Mask" "B.Paste")
			(net "P5V_A_2")
		)
		(pad "2" smd rect
			(at -0.0635 0 90)
			(size 0.1778 0.254)
			(layers "B.Cu" "B.Mask" "B.Paste")
			(net "P5V_B_CC")
		)
	)
	(footprint ""
		(layer "B.Cu")
		(at 471.722704 -222.569786)
		(property "Reference" "L8"
			(at 0 0 0)
			(layer "B.SilkS")
			(hide yes)
			(effects
				(font
					(size 1.27 1.27)
				)
				(justify mirror)
			)
		)
		(property "Value" "IND-1UH-191-GP"
			(at 6.7818 -2.1082 0)
			(unlocked yes)
			(layer "B.Fab")
			(hide yes)
			(effects
				(font
					(size 1.016 1.016)
					(thickness 0.1524)
				)
				(justify mirror)
			)
		)
		(property "Device Type" "L109100-2430-UH119"
			(at 6.7818 -3.6322 0)
			(unlocked yes)
			(layer "B.Fab")
			(hide yes)
			(effects
				(font
					(size 1.016 1.016)
					(thickness 0.1524)
				)
				(justify mirror)
			)
		)
		(duplicate_pad_numbers_are_jumpers no)
		(fp_line
			(start -5.2578 -6.4262)
			(end -5.2578 6.4262)
			(stroke
				(width 0.1524)
				(type default)
			)
			(layer "B.SilkS")
		)
		(fp_line
			(start -5.2578 6.4262)
			(end 5.2578 6.4262)
			(stroke
				(width 0.1524)
				(type default)
			)
			(layer "B.SilkS")
		)
		(fp_line
			(start 5.2578 -6.4262)
			(end -5.2578 -6.4262)
			(stroke
				(width 0.1524)
				(type default)
			)
			(layer "B.SilkS")
		)
		(fp_line
			(start 5.2578 6.4262)
			(end 5.2578 -6.4262)
			(stroke
				(width 0.1524)
				(type default)
			)
			(layer "B.SilkS")
		)
		(fp_rect
			(start 5.0038 5.4229)
			(end -5.0038 -5.4229)
			(stroke
				(width 0)
				(type default)
			)
			(fill no)
			(layer "B.CrtYd")
		)
		(fp_poly
			(pts
				(xy 5.5118 6.5024) (xy 5.5118 -6.5024) (xy -5.5118 -6.5024) (xy -5.5118 -0.8509) (xy -5.0038 -0.8509)
				(xy -5.0038 -5.4229) (xy 5.0038 -5.4229) (xy 5.0038 5.4229) (xy -5.0038 5.4229) (xy -5.0038 -0.8382)
				(xy -5.5118 -0.8382) (xy -5.5118 6.5024)
			)
			(stroke
				(width 0)
				(type default)
			)
			(fill no)
			(layer "B.CrtYd")
		)
		(fp_rect
			(start 5.5118 6.5024)
			(end -5.5118 -6.5024)
			(stroke
				(width 0)
				(type default)
			)
			(fill no)
			(layer "B.Fab")
		)
		(pad "1" smd rect
			(at 0 -4.396994 180)
			(size 3.5052 3.556)
			(layers "B.Cu" "B.Mask" "B.Paste")
			(net "P5V_D_LL")
		)
		(pad "2" smd rect
			(at 0 4.396994 180)
			(size 3.5052 3.556)
			(layers "B.Cu" "B.Mask" "B.Paste")
			(net "P5V_A_4")
		)
	)
	(footprint ""
		(layer "B.Cu")
		(at 65.5574 -139.3698)
		(property "Reference" "TC10"
			(at 0 0 0)
			(layer "B.SilkS")
			(hide yes)
			(effects
				(font
					(size 1.27 1.27)
				)
				(justify mirror)
			)
		)
		(property "Value" "ST220U10VDM-LGP"
			(at 0 -9.6012 0)
			(unlocked yes)
			(layer "B.Fab")
			(hide yes)
			(effects
				(font
					(size 1.016 1.016)
					(thickness 0.1524)
				)
				(justify mirror)
			)
		)
		(property "Device Type" "CT7343H119"
			(at 0 -11.1252 0)
			(unlocked yes)
			(layer "B.Fab")
			(hide yes)
			(effects
				(font
					(size 1.016 1.016)
					(thickness 0.1524)
				)
				(justify mirror)
			)
		)
		(duplicate_pad_numbers_are_jumpers no)
		(fp_line
			(start -2.286 -4.8768)
			(end 2.286 -4.8768)
			(stroke
				(width 0.1524)
				(type default)
			)
			(layer "B.SilkS")
		)
		(fp_line
			(start -2.286 -2.032)
			(end -2.286 -4.8768)
			(stroke
				(width 0.1524)
				(type default)
			)
			(layer "B.SilkS")
		)
		(fp_line
			(start -2.286 2.032)
			(end -2.286 4.8768)
			(stroke
				(width 0.1524)
				(type default)
			)
			(layer "B.SilkS")
		)
		(fp_line
			(start -2.286 4.8768)
			(end 2.286 4.8768)
			(stroke
				(width 0.1524)
				(type default)
			)
			(layer "B.SilkS")
		)
		(fp_line
			(start -2.1082 -4.699)
			(end 2.1082 -4.699)
			(stroke
				(width 0.508)
				(type default)
			)
			(layer "B.SilkS")
		)
		(fp_line
			(start 2.286 -4.8768)
			(end 2.286 -2.032)
			(stroke
				(width 0.1524)
				(type default)
			)
			(layer "B.SilkS")
		)
		(fp_line
			(start 2.286 4.8768)
			(end 2.286 2.032)
			(stroke
				(width 0.1524)
				(type default)
			)
			(layer "B.SilkS")
		)
		(fp_rect
			(start 2.1463 3.6449)
			(end -2.1463 -3.6449)
			(stroke
				(width 0)
				(type default)
			)
			(fill no)
			(layer "B.CrtYd")
		)
		(fp_poly
			(pts
				(xy 2.54 4.953) (xy 2.54 4.2926) (xy 3.81 4.2926) (xy 3.81 -4.2926) (xy 2.54 -4.2926) (xy 2.54 -4.953)
				(xy -2.54 -4.953) (xy -2.54 -4.2926) (xy -3.81 -4.2926) (xy -3.81 -1.6256) (xy -2.1463 -1.6256)
				(xy -2.1463 -3.6449) (xy 2.1463 -3.6449) (xy 2.1463 3.6449) (xy -2.1463 3.6449) (xy -2.1463 -1.6129)
				(xy -3.81 -1.6129) (xy -3.81 4.2926) (xy -2.54 4.2926) (xy -2.54 4.953)
			)
			(stroke
				(width 0)
				(type default)
			)
			(fill no)
			(layer "B.CrtYd")
		)
		(fp_rect
			(start -2.54 4.2926)
			(end -3.81 -4.2926)
			(stroke
				(width 0)
				(type default)
			)
			(fill no)
			(layer "B.Fab")
		)
		(fp_rect
			(start 2.54 4.953)
			(end -2.54 -4.953)
			(stroke
				(width 0)
				(type default)
			)
			(fill no)
			(layer "B.Fab")
		)
		(fp_rect
			(start 3.81 4.2926)
			(end 2.54 -4.2926)
			(stroke
				(width 0)
				(type default)
			)
			(fill no)
			(layer "B.Fab")
		)
		(pad "1" smd rect
			(at 0 -3.1496 180)
			(size 2.413 2.286)
			(layers "B.Cu" "B.Mask" "B.Paste")
			(net "P5V_A_2")
		)
		(pad "2" smd rect
			(at 0 3.1496 180)
			(size 2.413 2.286)
			(layers "B.Cu" "B.Mask" "B.Paste")
			(net "GND")
		)
		(zone
			(layer "B.Cu")
			(hatch none 0.5)
			(connect_pads
				(clearance 0)
			)
			(min_thickness 0.25)
			(keepout
				(tracks allowed)
				(vias not_allowed)
				(pads allowed)
				(copperpour not_allowed)
				(footprints allowed)
			)
			(placement
				(enabled no)
				(sheetname "")
			)
			(fill
				(thermal_gap 0.5)
				(thermal_bridge_width 0.5)
				(island_removal_mode 0)
			)
			(polygon
				(pts
					(xy 64.0461 -141.0589) (xy 64.0461 -143.9672) (xy 67.0687 -143.9672) (xy 67.0687 -141.0716) (xy 67.0687 -140.7414)
					(xy 64.0461 -140.7414)
				)
			)
		)
		(zone
			(layer "B.Cu")
			(hatch none 0.5)
			(connect_pads
				(clearance 0)
			)
			(min_thickness 0.25)
			(keepout
				(tracks allowed)
				(vias not_allowed)
				(pads allowed)
				(copperpour not_allowed)
				(footprints allowed)
			)
			(placement
				(enabled no)
				(sheetname "")
			)
			(fill
				(thermal_gap 0.5)
				(thermal_bridge_width 0.5)
				(island_removal_mode 0)
			)
			(polygon
				(pts
					(xy 67.0687 -134.7724) (xy 64.0461 -134.7724) (xy 64.0461 -137.668) (xy 64.0461 -137.9982) (xy 67.0687 -137.9982)
					(xy 67.0687 -137.668)
				)
			)
		)
	)
)
